(kicad_pcb
	(version 20260206)
	(generator "pcbnew")
	(generator_version "10.0")
	(general
		(thickness 1.6)
		(legacy_teardrops no)
	)
	(paper "A4")
	(title_block
		(title "Bryce Canyon_R.DPB_16317-1_OCP.brd")
		(comment 1 "Bryce Canyon / footprints 1927-1933 of 2099")
	)
	(layers
		(0 "F.Cu" signal "TOP")
		(4 "In1.Cu" signal "L2GND")
		(6 "In2.Cu" signal "L3")
		(8 "In3.Cu" signal "L4VCC")
		(10 "In4.Cu" signal "L5VCC")
		(12 "In5.Cu" signal "L6")
		(14 "In6.Cu" signal "L7GND")
		(2 "B.Cu" signal "BOTTOM")
		(9 "F.Adhes" user "F.Adhesive")
		(11 "B.Adhes" user "B.Adhesive")
		(13 "F.Paste" user "Package Geometry/Pastemask Top")
		(15 "B.Paste" user "Package Geometry/Pastemask Bottom")
		(5 "F.SilkS" user "Ref Des/Silkscreen Top")
		(7 "B.SilkS" user "Ref Des/Silkscreen Bottom")
		(1 "F.Mask" user "Board Geometry/Soldermask Top")
		(3 "B.Mask" user "Board Geometry/Soldermask Bottom")
		(17 "Dwgs.User" user "User.Drawings")
		(19 "Cmts.User" user "User.Comments")
		(21 "Eco1.User" user "User.Eco1")
		(23 "Eco2.User" user "User.Eco2")
		(25 "Edge.Cuts" user "Board Geometry/Outline")
		(27 "Margin" user)
		(31 "F.CrtYd" user "Package Geometry/Place Bound Top")
		(29 "B.CrtYd" user "Package Geometry/Place Bound Bottom")
		(35 "F.Fab" user "Ref Des/Assembly Top")
		(33 "B.Fab" user "Ref Des/Assembly Bottom")
	)
	(footprint ""
		(layer "F.Cu")
		(at 150.114 -157.226)
		(property "Reference" "C242"
			(at 0 0 0)
			(layer "F.SilkS")
			(hide yes)
			(effects
				(font
					(size 1.27 1.27)
				)
			)
		)
		(property "Value" "SC4D7U25V5KX-1-GP"
			(at -0.0762 -6.1214 0)
			(unlocked yes)
			(layer "F.Fab")
			(hide yes)
			(effects
				(font
					(size 1.016 1.016)
					(thickness 0.1524)
				)
			)
		)
		(property "Device Type" "C805H58"
			(at -0.0762 -8.1534 0)
			(unlocked yes)
			(layer "F.Fab")
			(hide yes)
			(effects
				(font
					(size 1.016 1.016)
					(thickness 0.1524)
				)
			)
		)
		(duplicate_pad_numbers_are_jumpers no)
		(fp_line
			(start 0.635 0)
			(end -0.635 0)
			(stroke
				(width 0.508)
				(type default)
			)
			(layer "F.SilkS")
		)
		(fp_rect
			(start -0.9652 1.778)
			(end 0.9652 -1.778)
			(stroke
				(width 0)
				(type default)
			)
			(fill no)
			(layer "F.CrtYd")
		)
		(fp_poly
			(pts
				(xy -0.9652 -1.778) (xy 0.9652 -1.778) (xy 0.9652 1.778) (xy -0.9652 1.778)
			)
			(stroke
				(width 0)
				(type default)
			)
			(fill no)
			(layer "F.Fab")
		)
		(pad "1" smd rect
			(at 0 -0.9652)
			(size 1.397 1.143)
			(layers "F.Cu" "F.Mask" "F.Paste")
			(net "P12V_HDD16")
		)
		(pad "2" smd rect
			(at 0 0.9652)
			(size 1.397 1.143)
			(layers "F.Cu" "F.Mask" "F.Paste")
			(net "GND")
		)
	)
	(footprint ""
		(layer "F.Cu")
		(at 109.474 -131.572 90)
		(property "Reference" "R429"
			(at 0 0 90)
			(layer "F.SilkS")
			(hide yes)
			(effects
				(font
					(size 1.27 1.27)
				)
			)
		)
		(property "Value" "4K7R2J-2-GP"
			(at 0.064008 -3.993896 90)
			(unlocked yes)
			(layer "F.Fab")
			(hide yes)
			(effects
				(font
					(size 1.016 1.016)
					(thickness 0.1524)
				)
			)
		)
		(property "Device Type" "R402H16"
			(at 0.064008 -5.517896 90)
			(unlocked yes)
			(layer "F.Fab")
			(hide yes)
			(effects
				(font
					(size 1.016 1.016)
					(thickness 0.1524)
				)
			)
		)
		(duplicate_pad_numbers_are_jumpers no)
		(fp_line
			(start 0.508 -0.9398)
			(end -0.508 -0.9398)
			(stroke
				(width 0.1524)
				(type default)
			)
			(layer "F.SilkS")
		)
		(fp_line
			(start -0.508 -0.9398)
			(end -0.508 0.9398)
			(stroke
				(width 0.1524)
				(type default)
			)
			(layer "F.SilkS")
		)
		(fp_rect
			(start -0.508 0.9398)
			(end 0.508 -0.9398)
			(stroke
				(width 0)
				(type default)
			)
			(fill no)
			(layer "F.CrtYd")
		)
		(fp_rect
			(start -0.508 0.9398)
			(end 0.508 -0.9398)
			(stroke
				(width 0)
				(type default)
			)
			(fill no)
			(layer "F.Fab")
		)
		(pad "1" smd custom
			(at 0 -0.4445 90)
			(size 0.1397 0.1397)
			(layers "F.Cu" "F.Mask" "F.Paste")
			(net "P12V_B")
			(options
				(clearance outline)
				(anchor circle)
			)
			(primitives
				(gr_poly
					(pts
						(arc
							(start -0.1778 -0.2794)
							(mid -0.249642 -0.249642)
							(end -0.2794 -0.1778)
						)
						(arc
							(start -0.2794 0.1778)
							(mid -0.249642 0.249642)
							(end -0.1778 0.2794)
						)
						(arc
							(start 0.1778 0.2794)
							(mid 0.249642 0.249642)
							(end 0.2794 0.1778)
						)
						(arc
							(start 0.2794 -0.1778)
							(mid 0.249642 -0.249642)
							(end 0.1778 -0.2794)
						)
					)
					(width 0)
					(fill yes)
				)
			)
		)
		(pad "2" smd custom
			(at 0 0.4445 90)
			(size 0.1397 0.1397)
			(layers "F.Cu" "F.Mask" "F.Paste")
			(net "SW_HDD_R15")
			(options
				(clearance outline)
				(anchor circle)
			)
			(primitives
				(gr_poly
					(pts
						(arc
							(start -0.1778 -0.2794)
							(mid -0.249642 -0.249642)
							(end -0.2794 -0.1778)
						)
						(arc
							(start -0.2794 0.1778)
							(mid -0.249642 0.249642)
							(end -0.1778 0.2794)
						)
						(arc
							(start 0.1778 0.2794)
							(mid 0.249642 0.249642)
							(end 0.2794 0.1778)
						)
						(arc
							(start 0.2794 -0.1778)
							(mid 0.249642 -0.249642)
							(end 0.1778 -0.2794)
						)
					)
					(width 0)
					(fill yes)
				)
			)
		)
	)
	(footprint ""
		(layer "F.Cu")
		(at 266.1158 -359.918 90)
		(property "Reference" "R1293"
			(at 0 0 90)
			(layer "F.SilkS")
			(hide yes)
			(effects
				(font
					(size 1.27 1.27)
				)
			)
		)
		(property "Value" "3K3R3F-GP"
			(at -0.0254 -2.5146 90)
			(unlocked yes)
			(layer "F.Fab")
			(hide yes)
			(effects
				(font
					(size 1.016 1.016)
					(thickness 0.1524)
				)
			)
		)
		(property "Device Type" "R603H22"
			(at -0.0254 -4.0386 90)
			(unlocked yes)
			(layer "F.Fab")
			(hide yes)
			(effects
				(font
					(size 1.016 1.016)
					(thickness 0.1524)
				)
			)
		)
		(duplicate_pad_numbers_are_jumpers no)
		(fp_line
			(start 0.2032 0)
			(end 0.4826 0)
			(stroke
				(width 0.2032)
				(type default)
			)
			(layer "F.SilkS")
		)
		(fp_line
			(start -0.4826 0)
			(end -0.2032 0)
			(stroke
				(width 0.2032)
				(type default)
			)
			(layer "F.SilkS")
		)
		(fp_rect
			(start -0.5842 1.3335)
			(end 0.5842 -1.3335)
			(stroke
				(width 0)
				(type default)
			)
			(fill no)
			(layer "F.CrtYd")
		)
		(fp_rect
			(start -0.5842 1.3335)
			(end 0.5842 -1.3335)
			(stroke
				(width 0)
				(type default)
			)
			(fill no)
			(layer "F.Fab")
		)
		(pad "1" smd custom
			(at 0 -0.762 90)
			(size 0.2159 0.2159)
			(layers "F.Cu" "F.Mask" "F.Paste")
			(net "P12V_IN")
			(options
				(clearance outline)
				(anchor circle)
			)
			(primitives
				(gr_poly
					(pts
						(arc
							(start -0.3302 -0.4318)
							(mid -0.402042 -0.402042)
							(end -0.4318 -0.3302)
						)
						(arc
							(start -0.4318 0.3302)
							(mid -0.402042 0.402042)
							(end -0.3302 0.4318)
						)
						(arc
							(start 0.3302 0.4318)
							(mid 0.402042 0.402042)
							(end 0.4318 0.3302)
						)
						(arc
							(start 0.4318 -0.3302)
							(mid 0.402042 -0.402042)
							(end 0.3302 -0.4318)
						)
					)
					(width 0)
					(fill yes)
				)
			)
		)
		(pad "2" smd custom
			(at 0 0.762 90)
			(size 0.2159 0.2159)
			(layers "F.Cu" "F.Mask" "F.Paste")
			(net "VCCP_IN")
			(options
				(clearance outline)
				(anchor circle)
			)
			(primitives
				(gr_poly
					(pts
						(arc
							(start -0.3302 -0.4318)
							(mid -0.402042 -0.402042)
							(end -0.4318 -0.3302)
						)
						(arc
							(start -0.4318 0.3302)
							(mid -0.402042 0.402042)
							(end -0.3302 0.4318)
						)
						(arc
							(start 0.3302 0.4318)
							(mid 0.402042 0.402042)
							(end 0.4318 0.3302)
						)
						(arc
							(start 0.4318 -0.3302)
							(mid 0.402042 -0.402042)
							(end 0.3302 -0.4318)
						)
					)
					(width 0)
					(fill yes)
				)
			)
		)
	)
	(footprint ""
		(layer "F.Cu")
		(at 333.5528 -155.6004 -90)
		(property "Reference" "R485"
			(at 0 0 270)
			(layer "F.SilkS")
			(hide yes)
			(effects
				(font
					(size 1.27 1.27)
				)
			)
		)
		(property "Value" "2R6F-GP"
			(at -0.0508 -4.8514 270)
			(unlocked yes)
			(layer "F.Fab")
			(hide yes)
			(effects
				(font
					(size 1.016 1.016)
					(thickness 0.1524)
				)
			)
		)
		(property "Device Type" "R1206H26"
			(at 0 -6.3754 270)
			(unlocked yes)
			(layer "F.Fab")
			(hide yes)
			(effects
				(font
					(size 1.016 1.016)
					(thickness 0.1524)
				)
			)
		)
		(duplicate_pad_numbers_are_jumpers no)
		(fp_line
			(start -1.016 2.2352)
			(end -1.016 -2.2352)
			(stroke
				(width 0.1524)
				(type default)
			)
			(layer "F.SilkS")
		)
		(fp_line
			(start 1.016 2.2352)
			(end -1.016 2.2352)
			(stroke
				(width 0.1524)
				(type default)
			)
			(layer "F.SilkS")
		)
		(fp_line
			(start -1.016 -2.2352)
			(end 1.016 -2.2352)
			(stroke
				(width 0.1524)
				(type default)
			)
			(layer "F.SilkS")
		)
		(fp_line
			(start 1.016 -2.2352)
			(end 1.016 2.2352)
			(stroke
				(width 0.1524)
				(type default)
			)
			(layer "F.SilkS")
		)
		(fp_rect
			(start -1.0922 2.3114)
			(end 1.0922 -2.3114)
			(stroke
				(width 0)
				(type default)
			)
			(fill no)
			(layer "F.CrtYd")
		)
		(fp_poly
			(pts
				(xy -1.0922 -2.3114) (xy 1.0922 -2.3114) (xy 1.0922 2.3114) (xy -1.0922 2.3114)
			)
			(stroke
				(width 0)
				(type default)
			)
			(fill no)
			(layer "F.Fab")
		)
		(pad "1" smd rect
			(at 0 -1.397 270)
			(size 1.651 1.27)
			(layers "F.Cu" "F.Mask" "F.Paste")
			(net "P12V_HDD18")
		)
		(pad "2" smd rect
			(at 0 1.397 270)
			(size 1.651 1.27)
			(layers "F.Cu" "F.Mask" "F.Paste")
			(net "12V_PRE_18")
		)
	)
	(footprint ""
		(layer "F.Cu")
		(at 433.737004 -358.3559)
		(property "Reference" "R146"
			(at 0 0 0)
			(layer "F.SilkS")
			(hide yes)
			(effects
				(font
					(size 1.27 1.27)
				)
			)
		)
		(property "Value" "200KR2F-L-GP"
			(at 0.064008 -3.993896 0)
			(unlocked yes)
			(layer "F.Fab")
			(hide yes)
			(effects
				(font
					(size 1.016 1.016)
					(thickness 0.1524)
				)
			)
		)
		(property "Device Type" "R402H16"
			(at 0.064008 -5.517896 0)
			(unlocked yes)
			(layer "F.Fab")
			(hide yes)
			(effects
				(font
					(size 1.016 1.016)
					(thickness 0.1524)
				)
			)
		)
		(duplicate_pad_numbers_are_jumpers no)
		(fp_line
			(start -0.508 -0.9398)
			(end -0.508 0.9398)
			(stroke
				(width 0.1524)
				(type default)
			)
			(layer "F.SilkS")
		)
		(fp_line
			(start 0.508 -0.9398)
			(end -0.508 -0.9398)
			(stroke
				(width 0.1524)
				(type default)
			)
			(layer "F.SilkS")
		)
		(fp_rect
			(start -0.508 0.9398)
			(end 0.508 -0.9398)
			(stroke
				(width 0)
				(type default)
			)
			(fill no)
			(layer "F.CrtYd")
		)
		(fp_rect
			(start -0.508 0.9398)
			(end 0.508 -0.9398)
			(stroke
				(width 0)
				(type default)
			)
			(fill no)
			(layer "F.Fab")
		)
		(pad "1" smd custom
			(at 0 -0.4445)
			(size 0.1397 0.1397)
			(layers "F.Cu" "F.Mask" "F.Paste")
			(net "GATE_FAN3")
			(options
				(clearance outline)
				(anchor circle)
			)
			(primitives
				(gr_poly
					(pts
						(arc
							(start -0.1778 -0.2794)
							(mid -0.249642 -0.249642)
							(end -0.2794 -0.1778)
						)
						(arc
							(start -0.2794 0.1778)
							(mid -0.249642 0.249642)
							(end -0.1778 0.2794)
						)
						(arc
							(start 0.1778 0.2794)
							(mid 0.249642 0.249642)
							(end 0.2794 0.1778)
						)
						(arc
							(start 0.2794 -0.1778)
							(mid 0.249642 -0.249642)
							(end 0.1778 -0.2794)
						)
					)
					(width 0)
					(fill yes)
				)
			)
		)
		(pad "2" smd custom
			(at 0 0.4445)
			(size 0.1397 0.1397)
			(layers "F.Cu" "F.Mask" "F.Paste")
			(net "GATE_FAN3_R")
			(options
				(clearance outline)
				(anchor circle)
			)
			(primitives
				(gr_poly
					(pts
						(arc
							(start -0.1778 -0.2794)
							(mid -0.249642 -0.249642)
							(end -0.2794 -0.1778)
						)
						(arc
							(start -0.2794 0.1778)
							(mid -0.249642 0.249642)
							(end -0.1778 0.2794)
						)
						(arc
							(start 0.1778 0.2794)
							(mid 0.249642 0.249642)
							(end 0.2794 0.1778)
						)
						(arc
							(start 0.2794 -0.1778)
							(mid 0.249642 -0.249642)
							(end 0.1778 -0.2794)
						)
					)
					(width 0)
					(fill yes)
				)
			)
		)
	)
	(footprint ""
		(layer "F.Cu")
		(at 171.831 -375.412 180)
		(property "Reference" "R982"
			(at 0 0 180)
			(layer "F.SilkS")
			(hide yes)
			(effects
				(font
					(size 1.27 1.27)
				)
			)
		)
		(property "Value" "100R2D-GP"
			(at 0.064008 -3.993896 180)
			(unlocked yes)
			(layer "F.Fab")
			(hide yes)
			(effects
				(font
					(size 1.016 1.016)
					(thickness 0.1524)
				)
			)
		)
		(property "Device Type" "R402H14"
			(at 0.064008 -5.517896 180)
			(unlocked yes)
			(layer "F.Fab")
			(hide yes)
			(effects
				(font
					(size 1.016 1.016)
					(thickness 0.1524)
				)
			)
		)
		(duplicate_pad_numbers_are_jumpers no)
		(fp_line
			(start 0.508 -0.9398)
			(end -0.508 -0.9398)
			(stroke
				(width 0.1524)
				(type default)
			)
			(layer "F.SilkS")
		)
		(fp_line
			(start -0.508 -0.9398)
			(end -0.508 0.9398)
			(stroke
				(width 0.1524)
				(type default)
			)
			(layer "F.SilkS")
		)
		(fp_rect
			(start -0.508 0.9398)
			(end 0.508 -0.9398)
			(stroke
				(width 0)
				(type default)
			)
			(fill no)
			(layer "F.CrtYd")
		)
		(fp_rect
			(start -0.508 0.9398)
			(end 0.508 -0.9398)
			(stroke
				(width 0)
				(type default)
			)
			(fill no)
			(layer "F.Fab")
		)
		(pad "1" smd custom
			(at 0 -0.4445 180)
			(size 0.1397 0.1397)
			(layers "F.Cu" "F.Mask" "F.Paste")
			(net "MB0_TEMP")
			(options
				(clearance outline)
				(anchor circle)
			)
			(primitives
				(gr_poly
					(pts
						(arc
							(start -0.1778 -0.2794)
							(mid -0.249642 -0.249642)
							(end -0.2794 -0.1778)
						)
						(arc
							(start -0.2794 0.1778)
							(mid -0.249642 0.249642)
							(end -0.1778 0.2794)
						)
						(arc
							(start 0.1778 0.2794)
							(mid 0.249642 0.249642)
							(end 0.2794 0.1778)
						)
						(arc
							(start 0.2794 -0.1778)
							(mid 0.249642 -0.249642)
							(end 0.1778 -0.2794)
						)
					)
					(width 0)
					(fill yes)
				)
			)
		)
		(pad "2" smd custom
			(at 0 0.4445 180)
			(size 0.1397 0.1397)
			(layers "F.Cu" "F.Mask" "F.Paste")
			(net "MB0_TEMP_B")
			(options
				(clearance outline)
				(anchor circle)
			)
			(primitives
				(gr_poly
					(pts
						(arc
							(start -0.1778 -0.2794)
							(mid -0.249642 -0.249642)
							(end -0.2794 -0.1778)
						)
						(arc
							(start -0.2794 0.1778)
							(mid -0.249642 0.249642)
							(end -0.1778 0.2794)
						)
						(arc
							(start 0.1778 0.2794)
							(mid 0.249642 0.249642)
							(end 0.2794 0.1778)
						)
						(arc
							(start 0.2794 -0.1778)
							(mid 0.249642 -0.249642)
							(end 0.1778 -0.2794)
						)
					)
					(width 0)
					(fill yes)
				)
			)
		)
	)
	(footprint ""
		(layer "F.Cu")
		(at 427.863 -243.586 180)
		(property "Reference" "R308"
			(at 0 0 180)
			(layer "F.SilkS")
			(hide yes)
			(effects
				(font
					(size 1.27 1.27)
				)
			)
		)
		(property "Value" "1KR2F-3-GP"
			(at 0.064008 -3.993896 180)
			(unlocked yes)
			(layer "F.Fab")
			(hide yes)
			(effects
				(font
					(size 1.016 1.016)
					(thickness 0.1524)
				)
			)
		)
		(property "Device Type" "R402H16"
			(at 0.064008 -5.517896 180)
			(unlocked yes)
			(layer "F.Fab")
			(hide yes)
			(effects
				(font
					(size 1.016 1.016)
					(thickness 0.1524)
				)
			)
		)
		(duplicate_pad_numbers_are_jumpers no)
		(fp_line
			(start 0.508 -0.9398)
			(end -0.508 -0.9398)
			(stroke
				(width 0.1524)
				(type default)
			)
			(layer "F.SilkS")
		)
		(fp_line
			(start -0.508 -0.9398)
			(end -0.508 0.9398)
			(stroke
				(width 0.1524)
				(type default)
			)
			(layer "F.SilkS")
		)
		(fp_rect
			(start -0.508 0.9398)
			(end 0.508 -0.9398)
			(stroke
				(width 0)
				(type default)
			)
			(fill no)
			(layer "F.CrtYd")
		)
		(fp_rect
			(start -0.508 0.9398)
			(end 0.508 -0.9398)
			(stroke
				(width 0)
				(type default)
			)
			(fill no)
			(layer "F.Fab")
		)
		(pad "1" smd custom
			(at 0 -0.4445 180)
			(size 0.1397 0.1397)
			(layers "F.Cu" "F.Mask" "F.Paste")
			(net "P3V3_STBY_B")
			(options
				(clearance outline)
				(anchor circle)
			)
			(primitives
				(gr_poly
					(pts
						(arc
							(start -0.1778 -0.2794)
							(mid -0.249642 -0.249642)
							(end -0.2794 -0.1778)
						)
						(arc
							(start -0.2794 0.1778)
							(mid -0.249642 0.249642)
							(end -0.1778 0.2794)
						)
						(arc
							(start 0.1778 0.2794)
							(mid 0.249642 0.249642)
							(end 0.2794 0.1778)
						)
						(arc
							(start 0.2794 -0.1778)
							(mid 0.249642 -0.249642)
							(end 0.1778 -0.2794)
						)
					)
					(width 0)
					(fill yes)
				)
			)
		)
		(pad "2" smd custom
			(at 0 0.4445 180)
			(size 0.1397 0.1397)
			(layers "F.Cu" "F.Mask" "F.Paste")
			(net "SW_PWR_R_HDD9")
			(options
				(clearance outline)
				(anchor circle)
			)
			(primitives
				(gr_poly
					(pts
						(arc
							(start -0.1778 -0.2794)
							(mid -0.249642 -0.249642)
							(end -0.2794 -0.1778)
						)
						(arc
							(start -0.2794 0.1778)
							(mid -0.249642 0.249642)
							(end -0.1778 0.2794)
						)
						(arc
							(start 0.1778 0.2794)
							(mid 0.249642 0.249642)
							(end 0.2794 0.1778)
						)
						(arc
							(start 0.2794 -0.1778)
							(mid 0.249642 -0.249642)
							(end 0.1778 -0.2794)
						)
					)
					(width 0)
					(fill yes)
				)
			)
		)
	)
)
